# BASEBOARD_FAB2 (Tioga Pass) — schematic netlist excerpt (pin names and nets, part order shuffled) for the footprints in the layout excerpt that follows; sources: Cadence DE-HDL packaged netlist, KiCad conversion of Wiwynn_Tioga_Pass_MB.brd

C6B5  CAP  0.22UF 16V 10% X7R  pkg 0402  page 105 : A = P3E_CPU0_PE1_PCH_TXP<15> ; B = P3E_CPU0_PE1_PCH_C_TXP<15>
R7D31  RES  33.2 1% CHIP  pkg 0402  page 92 : A = FM_CPU_ERR2_LVT3_R_N ; B = FM_CPU_ERR2_LVT3_N
R1T15  RES  0.0 5% EMPTY  pkg 0402  page 145 : A = FM_BMC_ONCTL_N ; B = FM_BMC_ONCTL_R_N

(kicad_pcb
	(version 20260206)
	(generator "pcbnew")
	(generator_version "10.0")
	(general
		(thickness 1.6)
		(legacy_teardrops no)
	)
	(paper "A4")
	(title_block
		(title "Wiwynn_Tioga_Pass_MB.brd")
		(comment 1 "Tioga Pass / footprints 1840-1842 of 4770")
	)
	(layers
		(0 "F.Cu" signal "TOP")
		(4 "In1.Cu" signal "L2GND")
		(6 "In2.Cu" signal "L3")
		(8 "In3.Cu" signal "L4GND")
		(10 "In4.Cu" signal "L5")
		(12 "In5.Cu" signal "L6GND")
		(14 "In6.Cu" signal "L7VCC")
		(16 "In7.Cu" signal "L8VCC")
		(18 "In8.Cu" signal "L9GND")
		(20 "In9.Cu" signal "L10")
		(22 "In10.Cu" signal "L11GND")
		(24 "In11.Cu" signal "L12")
		(26 "In12.Cu" signal "L13GND")
		(2 "B.Cu" signal "BOTTOM")
		(9 "F.Adhes" user "F.Adhesive")
		(11 "B.Adhes" user "B.Adhesive")
		(13 "F.Paste" user "Package Geometry/Pastemask Top")
		(15 "B.Paste" user "Package Geometry/Pastemask Bottom")
		(5 "F.SilkS" user "Ref Des/Silkscreen Top")
		(7 "B.SilkS" user "Ref Des/Silkscreen Bottom")
		(1 "F.Mask" user "Board Geometry/Soldermask Top")
		(3 "B.Mask" user "Board Geometry/Soldermask Bottom")
		(17 "Dwgs.User" user "User.Drawings")
		(19 "Cmts.User" user "User.Comments")
		(21 "Eco1.User" user "User.Eco1")
		(23 "Eco2.User" user "User.Eco2")
		(25 "Edge.Cuts" user "Board Geometry/Outline")
		(27 "Margin" user)
		(31 "F.CrtYd" user "Package Geometry/Place Bound Top")
		(29 "B.CrtYd" user "Package Geometry/Place Bound Bottom")
		(35 "F.Fab" user "Ref Des/Assembly Top")
		(33 "B.Fab" user "Ref Des/Assembly Bottom")
	)
	(footprint ""
		(layer "F.Cu")
		(at 418.554408 -48.953166)
		(property "Reference" "R1T15"
			(at -0.8382 -0.67818 0)
			(unlocked yes)
			(layer "F.SilkS")
			(effects
				(font
					(size 0.4064 0.254)
					(thickness 0.1524)
				)
				(justify left)
			)
		)
		(property "Value" ""
			(at 0 0 0)
			(layer "F.Fab")
			(effects
				(font
					(size 1.27 1.27)
				)
			)
		)
		(duplicate_pad_numbers_are_jumpers no)
		(fp_poly
			(pts
				(xy -0.2794 -0.1016) (xy 0.2794 -0.1016) (xy 0.2794 0.9906) (xy -0.2794 0.9906)
			)
			(stroke
				(width 0)
				(type default)
			)
			(fill no)
			(layer "F.CrtYd")
		)
		(fp_line
			(start -0.2794 -0.1016)
			(end -0.2794 0.9906)
			(stroke
				(width 0.1)
				(type default)
			)
			(layer "F.Fab")
		)
		(fp_line
			(start -0.2794 0.9906)
			(end 0.2794 0.9906)
			(stroke
				(width 0.1)
				(type default)
			)
			(layer "F.Fab")
		)
		(fp_line
			(start 0.2794 -0.1016)
			(end -0.2794 -0.1016)
			(stroke
				(width 0.1)
				(type default)
			)
			(layer "F.Fab")
		)
		(fp_line
			(start 0.2794 0.9906)
			(end 0.2794 -0.1016)
			(stroke
				(width 0.1)
				(type default)
			)
			(layer "F.Fab")
		)
		(pad "1" smd rect
			(at 0 0)
			(size 0.508 0.508)
			(layers "F.Cu" "F.Mask" "F.Paste")
			(net "FM_BMC_ONCTL_N")
		)
		(pad "2" smd rect
			(at 0 0.889)
			(size 0.508 0.508)
			(layers "F.Cu" "F.Mask" "F.Paste")
			(net "FM_BMC_ONCTL_R_N")
		)
		(zone
			(layer "F.Cu")
			(hatch none 0.5)
			(connect_pads
				(clearance 0)
			)
			(min_thickness 0.25)
			(keepout
				(tracks allowed)
				(vias not_allowed)
				(pads allowed)
				(copperpour not_allowed)
				(footprints allowed)
			)
			(placement
				(enabled no)
				(sheetname "")
			)
			(fill
				(thermal_gap 0.5)
				(thermal_bridge_width 0.5)
				(island_removal_mode 0)
			)
			(polygon
				(pts
					(xy 418.300408 -48.699166) (xy 418.808408 -48.699166) (xy 418.808408 -48.318166) (xy 418.300408 -48.318166)
				)
			)
		)
		(zone
			(layer "F.Cu")
			(hatch none 0.5)
			(connect_pads
				(clearance 0)
			)
			(min_thickness 0.25)
			(keepout
				(tracks not_allowed)
				(vias allowed)
				(pads allowed)
				(copperpour not_allowed)
				(footprints allowed)
			)
			(placement
				(enabled no)
				(sheetname "")
			)
			(fill
				(thermal_gap 0.5)
				(thermal_bridge_width 0.5)
				(island_removal_mode 0)
			)
			(polygon
				(pts
					(xy 418.300408 -48.318166) (xy 418.808408 -48.318166) (xy 418.808408 -48.699166) (xy 418.300408 -48.699166)
				)
			)
		)
	)
	(footprint ""
		(layer "F.Cu")
		(at 320.6115 -123.317 90)
		(property "Reference" "C6B5"
			(at -0.8382 -0.67818 90)
			(unlocked yes)
			(layer "F.SilkS")
			(effects
				(font
					(size 0.4064 0.254)
					(thickness 0.1524)
				)
				(justify left)
			)
		)
		(property "Value" ""
			(at 0 0 90)
			(layer "F.Fab")
			(effects
				(font
					(size 1.27 1.27)
				)
			)
		)
		(duplicate_pad_numbers_are_jumpers no)
		(fp_poly
			(pts
				(xy 0.3048 -0.1016) (xy 0.3048 0.9906) (xy -0.3048 0.9906) (xy -0.3048 -0.1016)
			)
			(stroke
				(width 0)
				(type default)
			)
			(fill no)
			(layer "F.CrtYd")
		)
		(fp_line
			(start 0.3048 -0.1016)
			(end -0.3048 -0.1016)
			(stroke
				(width 0.1)
				(type default)
			)
			(layer "F.Fab")
		)
		(fp_line
			(start -0.3048 -0.1016)
			(end -0.3048 0.9906)
			(stroke
				(width 0.1)
				(type default)
			)
			(layer "F.Fab")
		)
		(fp_line
			(start 0.3048 0.9906)
			(end 0.3048 -0.1016)
			(stroke
				(width 0.1)
				(type default)
			)
			(layer "F.Fab")
		)
		(fp_line
			(start -0.3048 0.9906)
			(end 0.3048 0.9906)
			(stroke
				(width 0.1)
				(type default)
			)
			(layer "F.Fab")
		)
		(pad "1" smd rect
			(at 0 0 90)
			(size 0.508 0.508)
			(layers "F.Cu" "F.Mask" "F.Paste")
			(net "P3E_CPU0_PE1_PCH_TXP<15>")
		)
		(pad "2" smd rect
			(at 0 0.889 90)
			(size 0.508 0.508)
			(layers "F.Cu" "F.Mask" "F.Paste")
			(net "P3E_CPU0_PE1_PCH_C_TXP<15>")
		)
		(zone
			(layer "F.Cu")
			(hatch none 0.5)
			(connect_pads
				(clearance 0)
			)
			(min_thickness 0.25)
			(keepout
				(tracks allowed)
				(vias not_allowed)
				(pads allowed)
				(copperpour not_allowed)
				(footprints allowed)
			)
			(placement
				(enabled no)
				(sheetname "")
			)
			(fill
				(thermal_gap 0.5)
				(thermal_bridge_width 0.5)
				(island_removal_mode 0)
			)
			(polygon
				(pts
					(xy 320.8655 -123.063) (xy 320.8655 -123.571) (xy 321.2465 -123.571) (xy 321.2465 -123.063)
				)
			)
		)
		(zone
			(layer "F.Cu")
			(hatch none 0.5)
			(connect_pads
				(clearance 0)
			)
			(min_thickness 0.25)
			(keepout
				(tracks not_allowed)
				(vias allowed)
				(pads allowed)
				(copperpour not_allowed)
				(footprints allowed)
			)
			(placement
				(enabled no)
				(sheetname "")
			)
			(fill
				(thermal_gap 0.5)
				(thermal_bridge_width 0.5)
				(island_removal_mode 0)
			)
			(polygon
				(pts
					(xy 321.2465 -123.063) (xy 321.2465 -123.571) (xy 320.8655 -123.571) (xy 320.8655 -123.063)
				)
			)
		)
	)
	(footprint ""
		(layer "F.Cu")
		(at 394.6525 -76.581 90)
		(property "Reference" "R7D31"
			(at 0 0 90)
			(layer "F.SilkS")
			(hide yes)
			(effects
				(font
					(size 1.27 1.27)
				)
			)
		)
		(property "Value" ""
			(at 0 0 90)
			(layer "F.Fab")
			(effects
				(font
					(size 1.27 1.27)
				)
			)
		)
		(duplicate_pad_numbers_are_jumpers no)
		(fp_poly
			(pts
				(xy -0.2794 -0.1016) (xy 0.2794 -0.1016) (xy 0.2794 0.9906) (xy -0.2794 0.9906)
			)
			(stroke
				(width 0)
				(type default)
			)
			(fill no)
			(layer "F.CrtYd")
		)
		(fp_line
			(start 0.2794 -0.1016)
			(end -0.2794 -0.1016)
			(stroke
				(width 0.1)
				(type default)
			)
			(layer "F.Fab")
		)
		(fp_line
			(start -0.2794 -0.1016)
			(end -0.2794 0.9906)
			(stroke
				(width 0.1)
				(type default)
			)
			(layer "F.Fab")
		)
		(fp_line
			(start 0.2794 0.9906)
			(end 0.2794 -0.1016)
			(stroke
				(width 0.1)
				(type default)
			)
			(layer "F.Fab")
		)
		(fp_line
			(start -0.2794 0.9906)
			(end 0.2794 0.9906)
			(stroke
				(width 0.1)
				(type default)
			)
			(layer "F.Fab")
		)
		(pad "1" smd rect
			(at 0 0 90)
			(size 0.508 0.508)
			(layers "F.Cu" "F.Mask" "F.Paste")
			(net "FM_CPU_ERR2_LVT3_R_N")
		)
		(pad "2" smd rect
			(at 0 0.889 90)
			(size 0.508 0.508)
			(layers "F.Cu" "F.Mask" "F.Paste")
			(net "FM_CPU_ERR2_LVT3_N")
		)
		(zone
			(layer "F.Cu")
			(hatch none 0.5)
			(connect_pads
				(clearance 0)
			)
			(min_thickness 0.25)
			(keepout
				(tracks allowed)
				(vias not_allowed)
				(pads allowed)
				(copperpour not_allowed)
				(footprints allowed)
			)
			(placement
				(enabled no)
				(sheetname "")
			)
			(fill
				(thermal_gap 0.5)
				(thermal_bridge_width 0.5)
				(island_removal_mode 0)
			)
			(polygon
				(pts
					(xy 394.9065 -76.327) (xy 394.9065 -76.835) (xy 395.2875 -76.835) (xy 395.2875 -76.327)
				)
			)
		)
		(zone
			(layer "F.Cu")
			(hatch none 0.5)
			(connect_pads
				(clearance 0)
			)
			(min_thickness 0.25)
			(keepout
				(tracks not_allowed)
				(vias allowed)
				(pads allowed)
				(copperpour not_allowed)
				(footprints allowed)
			)
			(placement
				(enabled no)
				(sheetname "")
			)
			(fill
				(thermal_gap 0.5)
				(thermal_bridge_width 0.5)
				(island_removal_mode 0)
			)
			(polygon
				(pts
					(xy 395.2875 -76.327) (xy 395.2875 -76.835) (xy 394.9065 -76.835) (xy 394.9065 -76.327)
				)
			)
		)
	)
)
